# S9S_MB_2U (Grand Teton) — schematic netlist excerpt (pin names and nets, part order shuffled) for the footprints in the layout excerpt that follows; sources: Cadence DE-HDL packaged netlist, KiCad conversion of 03242023_DA0F0TMBIJ0_F0T_Motherboard_J_brd_V01_OCP.brd

R4019  Q_RES  1K 1% CHIP  pkg 0402LF  page 226 : A = P0V62_CPU0_ERRS_VREF ; B = GND

(kicad_pcb
	(version 20260206)
	(generator "pcbnew")
	(generator_version "10.0")
	(general
		(thickness 1.6)
		(legacy_teardrops no)
	)
	(paper "A4")
	(title_block
		(title "03242023_DA0F0TMBIJ0_F0T_Motherboard_J_brd_V01_OCP.brd")
		(comment 1 "Grand Teton / footprints 2008-2008 of 6105")
	)
	(layers
		(0 "F.Cu" signal "TOP")
		(4 "In1.Cu" signal "GND")
		(6 "In2.Cu" signal "IN1")
		(8 "In3.Cu" signal "GND1")
		(10 "In4.Cu" signal "IN2")
		(12 "In5.Cu" signal "GND2")
		(14 "In6.Cu" signal "IN3")
		(16 "In7.Cu" signal "GND3")
		(18 "In8.Cu" signal "VCC")
		(20 "In9.Cu" signal "VCC1")
		(22 "In10.Cu" signal "GND4")
		(24 "In11.Cu" signal "IN4")
		(26 "In12.Cu" signal "GND5")
		(28 "In13.Cu" signal "IN5")
		(30 "In14.Cu" signal "GND6")
		(32 "In15.Cu" signal "IN6")
		(34 "In16.Cu" signal "GND7")
		(2 "B.Cu" signal "BOTTOM")
		(9 "F.Adhes" user "F.Adhesive")
		(11 "B.Adhes" user "B.Adhesive")
		(13 "F.Paste" user "Package Geometry/Pastemask Top")
		(15 "B.Paste" user "Package Geometry/Pastemask Bottom")
		(5 "F.SilkS" user "Ref Des/Silkscreen Top")
		(7 "B.SilkS" user "Ref Des/Silkscreen Bottom")
		(1 "F.Mask" user "Board Geometry/Soldermask Top")
		(3 "B.Mask" user "Board Geometry/Soldermask Bottom")
		(17 "Dwgs.User" user "User.Drawings")
		(19 "Cmts.User" user "User.Comments")
		(21 "Eco1.User" user "User.Eco1")
		(23 "Eco2.User" user "User.Eco2")
		(25 "Edge.Cuts" user "Board Geometry/Outline")
		(27 "Margin" user)
		(31 "F.CrtYd" user "Package Geometry/Place Bound Top")
		(29 "B.CrtYd" user "Package Geometry/Place Bound Bottom")
		(35 "F.Fab" user "Ref Des/Assembly Top")
		(33 "B.Fab" user "Ref Des/Assembly Bottom")
	)
	(footprint ""
		(layer "F.Cu")
		(at 114.73688 -104.079548 90)
		(property "Reference" "R4019"
			(at 0 0 90)
			(layer "F.SilkS")
			(hide yes)
			(effects
				(font
					(size 1.27 1.27)
				)
			)
		)
		(property "Value" ""
			(at 0 0 90)
			(layer "F.Fab")
			(effects
				(font
					(size 1.27 1.27)
				)
			)
		)
		(duplicate_pad_numbers_are_jumpers no)
		(fp_line
			(start 0.7874 -0.4064)
			(end 0.7874 0.4064)
			(stroke
				(width 0.1524)
				(type default)
			)
			(layer "F.SilkS")
		)
		(fp_line
			(start -0.7874 -0.4064)
			(end 0.7874 -0.4064)
			(stroke
				(width 0.1524)
				(type default)
			)
			(layer "F.SilkS")
		)
		(fp_line
			(start 0.7874 0.4064)
			(end -0.7874 0.4064)
			(stroke
				(width 0.1524)
				(type default)
			)
			(layer "F.SilkS")
		)
		(fp_line
			(start -0.7874 0.4064)
			(end -0.7874 -0.4064)
			(stroke
				(width 0.1524)
				(type default)
			)
			(layer "F.SilkS")
		)
		(fp_line
			(start -0.12065 -0.305054)
			(end -0.12065 -0.2794)
			(stroke
				(width 0.1)
				(type default)
			)
			(layer "F.Fab")
		)
		(fp_line
			(start -0.67945 -0.305054)
			(end -0.12065 -0.305054)
			(stroke
				(width 0.1)
				(type default)
			)
			(layer "F.Fab")
		)
		(fp_line
			(start 0.67945 -0.3048)
			(end 0.67945 0.3048)
			(stroke
				(width 0.1)
				(type default)
			)
			(layer "F.Fab")
		)
		(fp_line
			(start 0.12065 -0.3048)
			(end 0.67945 -0.3048)
			(stroke
				(width 0.1)
				(type default)
			)
			(layer "F.Fab")
		)
		(fp_line
			(start 0.12065 -0.2794)
			(end 0.12065 -0.3048)
			(stroke
				(width 0.1)
				(type default)
			)
			(layer "F.Fab")
		)
		(fp_line
			(start -0.12065 -0.2794)
			(end 0.12065 -0.2794)
			(stroke
				(width 0.1)
				(type default)
			)
			(layer "F.Fab")
		)
		(fp_line
			(start 0.120396 0.2794)
			(end -0.12065 0.2794)
			(stroke
				(width 0.1)
				(type default)
			)
			(layer "F.Fab")
		)
		(fp_line
			(start -0.12065 0.2794)
			(end -0.12065 0.3048)
			(stroke
				(width 0.1)
				(type default)
			)
			(layer "F.Fab")
		)
		(fp_line
			(start 0.67945 0.3048)
			(end 0.120396 0.3048)
			(stroke
				(width 0.1)
				(type default)
			)
			(layer "F.Fab")
		)
		(fp_line
			(start 0.120396 0.3048)
			(end 0.120396 0.2794)
			(stroke
				(width 0.1)
				(type default)
			)
			(layer "F.Fab")
		)
		(fp_line
			(start -0.12065 0.3048)
			(end -0.67945 0.3048)
			(stroke
				(width 0.1)
				(type default)
			)
			(layer "F.Fab")
		)
		(fp_line
			(start -0.67945 0.3048)
			(end -0.67945 -0.305054)
			(stroke
				(width 0.1)
				(type default)
			)
			(layer "F.Fab")
		)
		(pad "1" smd circle
			(at -0.40005 0 90)
			(size 0 0)
			(layers "F.Cu" "F.Mask" "F.Paste")
			(net "P0V62_CPU0_ERRS_VREF")
		)
		(pad "2" smd circle
			(at 0.40005 0 90)
			(size 0 0)
			(layers "F.Cu" "F.Mask" "F.Paste")
			(net "GND")
		)
	)
)
